(kicad_pcb
	(version 20260206)
	(generator "pcbnew")
	(generator_version "10.0")
	(general
		(thickness 1.6)
		(legacy_teardrops no)
	)
	(paper "A4")
	(title_block
		(title "01162023_DA0F0TEBIF0_F0T_Expander_BD_F_brd_V02_OCP.brd")
		(comment 1 "Grand Teton / footprints 6871-6877 of 9728")
	)
	(layers
		(0 "F.Cu" signal "TOP")
		(4 "In1.Cu" signal "GND")
		(6 "In2.Cu" signal "VCC")
		(8 "In3.Cu" signal "VCC1")
		(10 "In4.Cu" signal "GND1")
		(12 "In5.Cu" signal "IN1")
		(14 "In6.Cu" signal "GND2")
		(16 "In7.Cu" signal "IN2")
		(18 "In8.Cu" signal "GND3")
		(20 "In9.Cu" signal "IN3")
		(22 "In10.Cu" signal "GND4")
		(24 "In11.Cu" signal "IN4")
		(26 "In12.Cu" signal "GND5")
		(28 "In13.Cu" signal "IN5")
		(30 "In14.Cu" signal "GND6")
		(32 "In15.Cu" signal "IN6")
		(34 "In16.Cu" signal "GND7")
		(2 "B.Cu" signal "BOTTOM")
		(9 "F.Adhes" user "F.Adhesive")
		(11 "B.Adhes" user "B.Adhesive")
		(13 "F.Paste" user "Package Geometry/Pastemask Top")
		(15 "B.Paste" user "Package Geometry/Pastemask Bottom")
		(5 "F.SilkS" user "Ref Des/Silkscreen Top")
		(7 "B.SilkS" user "Ref Des/Silkscreen Bottom")
		(1 "F.Mask" user "Board Geometry/Soldermask Top")
		(3 "B.Mask" user "Board Geometry/Soldermask Bottom")
		(17 "Dwgs.User" user "User.Drawings")
		(19 "Cmts.User" user "User.Comments")
		(21 "Eco1.User" user "User.Eco1")
		(23 "Eco2.User" user "User.Eco2")
		(25 "Edge.Cuts" user "Board Geometry/Outline")
		(27 "Margin" user)
		(31 "F.CrtYd" user "Package Geometry/Place Bound Top")
		(29 "B.CrtYd" user "Package Geometry/Place Bound Bottom")
		(35 "F.Fab" user "Ref Des/Assembly Top")
		(33 "B.Fab" user "Ref Des/Assembly Bottom")
	)
	(footprint ""
		(layer "F.Cu")
		(at 365.92764 -308.397148 -90)
		(property "Reference" "C4361"
			(at 0 0 270)
			(layer "F.SilkS")
			(hide yes)
			(effects
				(font
					(size 1.27 1.27)
				)
			)
		)
		(property "Value" ""
			(at 0 0 270)
			(layer "F.Fab")
			(effects
				(font
					(size 1.27 1.27)
				)
			)
		)
		(duplicate_pad_numbers_are_jumpers no)
		(fp_line
			(start -1.2954 0.5842)
			(end -1.2954 -0.5842)
			(stroke
				(width 0.1524)
				(type default)
			)
			(layer "F.SilkS")
		)
		(fp_line
			(start 1.2954 0.5842)
			(end -1.2954 0.5842)
			(stroke
				(width 0.1524)
				(type default)
			)
			(layer "F.SilkS")
		)
		(fp_line
			(start -1.2954 -0.5842)
			(end 1.2954 -0.5842)
			(stroke
				(width 0.1524)
				(type default)
			)
			(layer "F.SilkS")
		)
		(fp_line
			(start 1.2954 -0.5842)
			(end 1.2954 0.5842)
			(stroke
				(width 0.1524)
				(type default)
			)
			(layer "F.SilkS")
		)
		(fp_line
			(start -0.8636 0.4572)
			(end -0.8636 0.4064)
			(stroke
				(width 0.1)
				(type default)
			)
			(layer "F.Fab")
		)
		(fp_line
			(start 0.8636 0.4572)
			(end -0.8636 0.4572)
			(stroke
				(width 0.1)
				(type default)
			)
			(layer "F.Fab")
		)
		(fp_line
			(start -1.1938 0.4064)
			(end -1.1938 -0.4064)
			(stroke
				(width 0.1)
				(type default)
			)
			(layer "F.Fab")
		)
		(fp_line
			(start -0.8636 0.4064)
			(end -1.1938 0.4064)
			(stroke
				(width 0.1)
				(type default)
			)
			(layer "F.Fab")
		)
		(fp_line
			(start 0.8636 0.4064)
			(end 0.8636 0.4572)
			(stroke
				(width 0.1)
				(type default)
			)
			(layer "F.Fab")
		)
		(fp_line
			(start 1.1938 0.4064)
			(end 0.8636 0.4064)
			(stroke
				(width 0.1)
				(type default)
			)
			(layer "F.Fab")
		)
		(fp_line
			(start -1.1938 -0.4064)
			(end -0.8636 -0.4064)
			(stroke
				(width 0.1)
				(type default)
			)
			(layer "F.Fab")
		)
		(fp_line
			(start -0.8636 -0.4064)
			(end -0.8636 -0.4572)
			(stroke
				(width 0.1)
				(type default)
			)
			(layer "F.Fab")
		)
		(fp_line
			(start 0.8636 -0.4064)
			(end 1.1938 -0.4064)
			(stroke
				(width 0.1)
				(type default)
			)
			(layer "F.Fab")
		)
		(fp_line
			(start 1.1938 -0.4064)
			(end 1.1938 0.4064)
			(stroke
				(width 0.1)
				(type default)
			)
			(layer "F.Fab")
		)
		(fp_line
			(start -0.8636 -0.4572)
			(end 0.8636 -0.4572)
			(stroke
				(width 0.1)
				(type default)
			)
			(layer "F.Fab")
		)
		(fp_line
			(start 0.8636 -0.4572)
			(end 0.8636 -0.4064)
			(stroke
				(width 0.1)
				(type default)
			)
			(layer "F.Fab")
		)
		(pad "1" smd rect
			(at -0.7366 0 180)
			(size 0.7112 0.8128)
			(layers "F.Cu" "F.Mask" "F.Paste")
			(net "P0V8_PEX3")
		)
		(pad "2" smd rect
			(at 0.7366 0 180)
			(size 0.7112 0.8128)
			(layers "F.Cu" "F.Mask" "F.Paste")
			(net "GND")
		)
	)
	(footprint ""
		(layer "F.Cu")
		(at 336.042 -167.005 180)
		(property "Reference" "R4742"
			(at 0 0 180)
			(layer "F.SilkS")
			(hide yes)
			(effects
				(font
					(size 1.27 1.27)
				)
			)
		)
		(property "Value" ""
			(at 0 0 180)
			(layer "F.Fab")
			(effects
				(font
					(size 1.27 1.27)
				)
			)
		)
		(duplicate_pad_numbers_are_jumpers no)
		(fp_line
			(start 0.7874 0.4064)
			(end -0.7874 0.4064)
			(stroke
				(width 0.1524)
				(type default)
			)
			(layer "F.SilkS")
		)
		(fp_line
			(start 0.7874 -0.4064)
			(end 0.7874 0.4064)
			(stroke
				(width 0.1524)
				(type default)
			)
			(layer "F.SilkS")
		)
		(fp_line
			(start -0.7874 0.4064)
			(end -0.7874 -0.4064)
			(stroke
				(width 0.1524)
				(type default)
			)
			(layer "F.SilkS")
		)
		(fp_line
			(start -0.7874 -0.4064)
			(end 0.7874 -0.4064)
			(stroke
				(width 0.1524)
				(type default)
			)
			(layer "F.SilkS")
		)
		(fp_line
			(start 0.67945 0.3048)
			(end 0.120396 0.3048)
			(stroke
				(width 0.1)
				(type default)
			)
			(layer "F.Fab")
		)
		(fp_line
			(start 0.67945 -0.3048)
			(end 0.67945 0.3048)
			(stroke
				(width 0.1)
				(type default)
			)
			(layer "F.Fab")
		)
		(fp_line
			(start 0.12065 -0.2794)
			(end 0.12065 -0.3048)
			(stroke
				(width 0.1)
				(type default)
			)
			(layer "F.Fab")
		)
		(fp_line
			(start 0.12065 -0.3048)
			(end 0.67945 -0.3048)
			(stroke
				(width 0.1)
				(type default)
			)
			(layer "F.Fab")
		)
		(fp_line
			(start 0.120396 0.3048)
			(end 0.120396 0.2794)
			(stroke
				(width 0.1)
				(type default)
			)
			(layer "F.Fab")
		)
		(fp_line
			(start 0.120396 0.2794)
			(end -0.12065 0.2794)
			(stroke
				(width 0.1)
				(type default)
			)
			(layer "F.Fab")
		)
		(fp_line
			(start -0.12065 0.3048)
			(end -0.67945 0.3048)
			(stroke
				(width 0.1)
				(type default)
			)
			(layer "F.Fab")
		)
		(fp_line
			(start -0.12065 0.2794)
			(end -0.12065 0.3048)
			(stroke
				(width 0.1)
				(type default)
			)
			(layer "F.Fab")
		)
		(fp_line
			(start -0.12065 -0.2794)
			(end 0.12065 -0.2794)
			(stroke
				(width 0.1)
				(type default)
			)
			(layer "F.Fab")
		)
		(fp_line
			(start -0.12065 -0.305054)
			(end -0.12065 -0.2794)
			(stroke
				(width 0.1)
				(type default)
			)
			(layer "F.Fab")
		)
		(fp_line
			(start -0.67945 0.3048)
			(end -0.67945 -0.305054)
			(stroke
				(width 0.1)
				(type default)
			)
			(layer "F.Fab")
		)
		(fp_line
			(start -0.67945 -0.305054)
			(end -0.12065 -0.305054)
			(stroke
				(width 0.1)
				(type default)
			)
			(layer "F.Fab")
		)
		(pad "1" smd circle
			(at -0.40005 0 180)
			(size 0 0)
			(layers "F.Cu" "F.Mask" "F.Paste")
			(net "SSD11_PEX_PWR_EN_R")
		)
		(pad "2" smd circle
			(at 0.40005 0 180)
			(size 0 0)
			(layers "F.Cu" "F.Mask" "F.Paste")
			(net "GND")
		)
	)
	(footprint ""
		(layer "F.Cu")
		(at 79.12608 -37.9349 90)
		(property "Reference" "R5549"
			(at 0 0 90)
			(layer "F.SilkS")
			(hide yes)
			(effects
				(font
					(size 1.27 1.27)
				)
			)
		)
		(property "Value" ""
			(at 0 0 90)
			(layer "F.Fab")
			(effects
				(font
					(size 1.27 1.27)
				)
			)
		)
		(duplicate_pad_numbers_are_jumpers no)
		(fp_line
			(start 0.7874 -0.4064)
			(end 0.7874 0.4064)
			(stroke
				(width 0.1524)
				(type default)
			)
			(layer "F.SilkS")
		)
		(fp_line
			(start -0.7874 -0.4064)
			(end 0.7874 -0.4064)
			(stroke
				(width 0.1524)
				(type default)
			)
			(layer "F.SilkS")
		)
		(fp_line
			(start 0.7874 0.4064)
			(end -0.7874 0.4064)
			(stroke
				(width 0.1524)
				(type default)
			)
			(layer "F.SilkS")
		)
		(fp_line
			(start -0.7874 0.4064)
			(end -0.7874 -0.4064)
			(stroke
				(width 0.1524)
				(type default)
			)
			(layer "F.SilkS")
		)
		(fp_line
			(start -0.12065 -0.305054)
			(end -0.12065 -0.2794)
			(stroke
				(width 0.1)
				(type default)
			)
			(layer "F.Fab")
		)
		(fp_line
			(start -0.67945 -0.305054)
			(end -0.12065 -0.305054)
			(stroke
				(width 0.1)
				(type default)
			)
			(layer "F.Fab")
		)
		(fp_line
			(start 0.67945 -0.3048)
			(end 0.67945 0.3048)
			(stroke
				(width 0.1)
				(type default)
			)
			(layer "F.Fab")
		)
		(fp_line
			(start 0.12065 -0.3048)
			(end 0.67945 -0.3048)
			(stroke
				(width 0.1)
				(type default)
			)
			(layer "F.Fab")
		)
		(fp_line
			(start 0.12065 -0.2794)
			(end 0.12065 -0.3048)
			(stroke
				(width 0.1)
				(type default)
			)
			(layer "F.Fab")
		)
		(fp_line
			(start -0.12065 -0.2794)
			(end 0.12065 -0.2794)
			(stroke
				(width 0.1)
				(type default)
			)
			(layer "F.Fab")
		)
		(fp_line
			(start 0.120396 0.2794)
			(end -0.12065 0.2794)
			(stroke
				(width 0.1)
				(type default)
			)
			(layer "F.Fab")
		)
		(fp_line
			(start -0.12065 0.2794)
			(end -0.12065 0.3048)
			(stroke
				(width 0.1)
				(type default)
			)
			(layer "F.Fab")
		)
		(fp_line
			(start 0.67945 0.3048)
			(end 0.120396 0.3048)
			(stroke
				(width 0.1)
				(type default)
			)
			(layer "F.Fab")
		)
		(fp_line
			(start 0.120396 0.3048)
			(end 0.120396 0.2794)
			(stroke
				(width 0.1)
				(type default)
			)
			(layer "F.Fab")
		)
		(fp_line
			(start -0.12065 0.3048)
			(end -0.67945 0.3048)
			(stroke
				(width 0.1)
				(type default)
			)
			(layer "F.Fab")
		)
		(fp_line
			(start -0.67945 0.3048)
			(end -0.67945 -0.305054)
			(stroke
				(width 0.1)
				(type default)
			)
			(layer "F.Fab")
		)
		(pad "1" smd circle
			(at -0.40005 0 90)
			(size 0 0)
			(layers "F.Cu" "F.Mask" "F.Paste")
			(net "SSD3_AUX_P3V3_EN_R")
		)
		(pad "2" smd circle
			(at 0.40005 0 90)
			(size 0 0)
			(layers "F.Cu" "F.Mask" "F.Paste")
			(net "SSD3_AUX_P3V3_EN")
		)
	)
	(footprint ""
		(layer "F.Cu")
		(at 461.76311 -254.344932 -90)
		(property "Reference" "C4412"
			(at 0 0 270)
			(layer "F.SilkS")
			(hide yes)
			(effects
				(font
					(size 1.27 1.27)
				)
			)
		)
		(property "Value" ""
			(at 0 0 270)
			(layer "F.Fab")
			(effects
				(font
					(size 1.27 1.27)
				)
			)
		)
		(duplicate_pad_numbers_are_jumpers no)
		(fp_line
			(start -1.524 0.762)
			(end -1.524 -0.762)
			(stroke
				(width 0.1524)
				(type default)
			)
			(layer "F.SilkS")
		)
		(fp_line
			(start 1.524 0.762)
			(end -1.524 0.762)
			(stroke
				(width 0.1524)
				(type default)
			)
			(layer "F.SilkS")
		)
		(fp_line
			(start -1.524 -0.762)
			(end 1.524 -0.762)
			(stroke
				(width 0.1524)
				(type default)
			)
			(layer "F.SilkS")
		)
		(fp_line
			(start 1.524 -0.762)
			(end 1.524 0.762)
			(stroke
				(width 0.1524)
				(type default)
			)
			(layer "F.SilkS")
		)
		(fp_line
			(start -1.1049 0.724916)
			(end 1.1049 0.724916)
			(stroke
				(width 0.1)
				(type default)
			)
			(layer "F.Fab")
		)
		(fp_line
			(start 1.1049 0.724916)
			(end 1.1049 -0.724916)
			(stroke
				(width 0.1)
				(type default)
			)
			(layer "F.Fab")
		)
		(fp_line
			(start -1.1049 -0.724916)
			(end -1.1049 0.724916)
			(stroke
				(width 0.1)
				(type default)
			)
			(layer "F.Fab")
		)
		(fp_line
			(start 1.1049 -0.724916)
			(end -1.1049 -0.724916)
			(stroke
				(width 0.1)
				(type default)
			)
			(layer "F.Fab")
		)
		(pad "1" smd rect
			(at -0.889 0 90)
			(size 1.016 1.27)
			(layers "F.Cu" "F.Mask" "F.Paste")
			(net "P1V25_SERDES_VDDPLL_PEX3_C10")
		)
		(pad "2" smd rect
			(at 0.889 0 90)
			(size 1.016 1.27)
			(layers "F.Cu" "F.Mask" "F.Paste")
			(net "GND")
		)
		(zone
			(layer "F.Cu")
			(hatch none 0.5)
			(connect_pads
				(clearance 0)
			)
			(min_thickness 0.25)
			(keepout
				(tracks not_allowed)
				(vias allowed)
				(pads allowed)
				(copperpour not_allowed)
				(footprints allowed)
			)
			(placement
				(enabled no)
				(sheetname "")
			)
			(fill
				(thermal_gap 0.5)
				(thermal_bridge_width 0.5)
				(island_removal_mode 0)
			)
			(polygon
				(pts
					(xy 462.488026 -254.675132) (xy 461.038194 -254.675132) (xy 461.038194 -254.014732) (xy 462.488026 -254.014732)
				)
			)
		)
	)
	(footprint ""
		(layer "F.Cu")
		(at 421.705532 -343.952322 90)
		(property "Reference" "C814"
			(at 0 0 90)
			(layer "F.SilkS")
			(hide yes)
			(effects
				(font
					(size 1.27 1.27)
				)
			)
		)
		(property "Value" ""
			(at 0 0 90)
			(layer "F.Fab")
			(effects
				(font
					(size 1.27 1.27)
				)
			)
		)
		(duplicate_pad_numbers_are_jumpers no)
		(fp_line
			(start 0.299974 -0.150114)
			(end 0.299974 0.150114)
			(stroke
				(width 0.1)
				(type default)
			)
			(layer "F.Fab")
		)
		(fp_line
			(start -0.299974 -0.150114)
			(end 0.299974 -0.150114)
			(stroke
				(width 0.1)
				(type default)
			)
			(layer "F.Fab")
		)
		(fp_line
			(start 0.299974 0.150114)
			(end -0.299974 0.150114)
			(stroke
				(width 0.1)
				(type default)
			)
			(layer "F.Fab")
		)
		(fp_line
			(start -0.299974 0.150114)
			(end -0.299974 -0.150114)
			(stroke
				(width 0.1)
				(type default)
			)
			(layer "F.Fab")
		)
		(pad "1" smd rect
			(at -0.2667 0 90)
			(size 0.3048 0.381)
			(layers "F.Cu" "F.Mask" "F.Paste")
			(net "P5E_PEX3_STN7_TX_DP<117>")
		)
		(pad "2" smd rect
			(at 0.2667 0 90)
			(size 0.3048 0.381)
			(layers "F.Cu" "F.Mask" "F.Paste")
			(net "P5E_PEX3_STN7_TX_C_DP<117>")
		)
	)
	(footprint ""
		(layer "F.Cu")
		(at 327.533 -214.249 180)
		(property "Reference" "R4155"
			(at 0 0 180)
			(layer "F.SilkS")
			(hide yes)
			(effects
				(font
					(size 1.27 1.27)
				)
			)
		)
		(property "Value" ""
			(at 0 0 180)
			(layer "F.Fab")
			(effects
				(font
					(size 1.27 1.27)
				)
			)
		)
		(duplicate_pad_numbers_are_jumpers no)
		(fp_line
			(start 0.7874 0.4064)
			(end -0.7874 0.4064)
			(stroke
				(width 0.1524)
				(type default)
			)
			(layer "F.SilkS")
		)
		(fp_line
			(start 0.7874 -0.4064)
			(end 0.7874 0.4064)
			(stroke
				(width 0.1524)
				(type default)
			)
			(layer "F.SilkS")
		)
		(fp_line
			(start -0.7874 0.4064)
			(end -0.7874 -0.4064)
			(stroke
				(width 0.1524)
				(type default)
			)
			(layer "F.SilkS")
		)
		(fp_line
			(start -0.7874 -0.4064)
			(end 0.7874 -0.4064)
			(stroke
				(width 0.1524)
				(type default)
			)
			(layer "F.SilkS")
		)
		(fp_line
			(start 0.67945 0.3048)
			(end 0.120396 0.3048)
			(stroke
				(width 0.1)
				(type default)
			)
			(layer "F.Fab")
		)
		(fp_line
			(start 0.67945 -0.3048)
			(end 0.67945 0.3048)
			(stroke
				(width 0.1)
				(type default)
			)
			(layer "F.Fab")
		)
		(fp_line
			(start 0.12065 -0.2794)
			(end 0.12065 -0.3048)
			(stroke
				(width 0.1)
				(type default)
			)
			(layer "F.Fab")
		)
		(fp_line
			(start 0.12065 -0.3048)
			(end 0.67945 -0.3048)
			(stroke
				(width 0.1)
				(type default)
			)
			(layer "F.Fab")
		)
		(fp_line
			(start 0.120396 0.3048)
			(end 0.120396 0.2794)
			(stroke
				(width 0.1)
				(type default)
			)
			(layer "F.Fab")
		)
		(fp_line
			(start 0.120396 0.2794)
			(end -0.12065 0.2794)
			(stroke
				(width 0.1)
				(type default)
			)
			(layer "F.Fab")
		)
		(fp_line
			(start -0.12065 0.3048)
			(end -0.67945 0.3048)
			(stroke
				(width 0.1)
				(type default)
			)
			(layer "F.Fab")
		)
		(fp_line
			(start -0.12065 0.2794)
			(end -0.12065 0.3048)
			(stroke
				(width 0.1)
				(type default)
			)
			(layer "F.Fab")
		)
		(fp_line
			(start -0.12065 -0.2794)
			(end 0.12065 -0.2794)
			(stroke
				(width 0.1)
				(type default)
			)
			(layer "F.Fab")
		)
		(fp_line
			(start -0.12065 -0.305054)
			(end -0.12065 -0.2794)
			(stroke
				(width 0.1)
				(type default)
			)
			(layer "F.Fab")
		)
		(fp_line
			(start -0.67945 0.3048)
			(end -0.67945 -0.305054)
			(stroke
				(width 0.1)
				(type default)
			)
			(layer "F.Fab")
		)
		(fp_line
			(start -0.67945 -0.305054)
			(end -0.12065 -0.305054)
			(stroke
				(width 0.1)
				(type default)
			)
			(layer "F.Fab")
		)
		(pad "1" smd circle
			(at -0.40005 0 180)
			(size 0 0)
			(layers "F.Cu" "F.Mask" "F.Paste")
			(net "PRSNT_SSD8_FPGA_N")
		)
		(pad "2" smd circle
			(at 0.40005 0 180)
			(size 0 0)
			(layers "F.Cu" "F.Mask" "F.Paste")
			(net "PRSNT_SSD8_FPGA_R_N")
		)
	)
	(footprint ""
		(layer "F.Cu")
		(at 39.280592 -125.519942)
		(property "Reference" "C42"
			(at 0 0 0)
			(layer "F.SilkS")
			(hide yes)
			(effects
				(font
					(size 1.27 1.27)
				)
			)
		)
		(property "Value" ""
			(at 0 0 0)
			(layer "F.Fab")
			(effects
				(font
					(size 1.27 1.27)
				)
			)
		)
		(duplicate_pad_numbers_are_jumpers no)
		(fp_line
			(start -0.299974 -0.150114)
			(end 0.299974 -0.150114)
			(stroke
				(width 0.1)
				(type default)
			)
			(layer "F.Fab")
		)
		(fp_line
			(start -0.299974 0.150114)
			(end -0.299974 -0.150114)
			(stroke
				(width 0.1)
				(type default)
			)
			(layer "F.Fab")
		)
		(fp_line
			(start 0.299974 -0.150114)
			(end 0.299974 0.150114)
			(stroke
				(width 0.1)
				(type default)
			)
			(layer "F.Fab")
		)
		(fp_line
			(start 0.299974 0.150114)
			(end -0.299974 0.150114)
			(stroke
				(width 0.1)
				(type default)
			)
			(layer "F.Fab")
		)
		(pad "1" smd rect
			(at -0.2667 0)
			(size 0.3048 0.381)
			(layers "F.Cu" "F.Mask" "F.Paste")
			(net "P5E_PEX0_STN1_TX_DP<27>")
		)
		(pad "2" smd rect
			(at 0.2667 0)
			(size 0.3048 0.381)
			(layers "F.Cu" "F.Mask" "F.Paste")
			(net "P5E_PEX0_STN1_TX_C_DP<27>")
		)
	)
)
